(kicad_pcb
	(version 20241229)
	(generator "pcbnew")
	(generator_version "9.0")
	(general
		(thickness 1.61)
		(legacy_teardrops no)
	)
	(paper "A3")
	(title_block
		(title "RDIMM DDR5 Tester")
		(date "2026-05-21")
		(rev "2.2.0")
		(company "Antmicro")
		(comment 9 "footprints 304-310 of 796")
	)
	(layers
		(0 "F.Cu" signal)
		(4 "In1.Cu" power)
		(6 "In2.Cu" mixed)
		(8 "In3.Cu" power)
		(10 "In4.Cu" mixed)
		(12 "In5.Cu" power)
		(14 "In6.Cu" mixed)
		(16 "In7.Cu" power)
		(18 "In8.Cu" power)
		(20 "In9.Cu" mixed)
		(22 "In10.Cu" power)
		(2 "B.Cu" signal)
		(9 "F.Adhes" user "F.Adhesive")
		(11 "B.Adhes" user "B.Adhesive")
		(13 "F.Paste" user)
		(15 "B.Paste" user)
		(5 "F.SilkS" user "F.Silkscreen")
		(7 "B.SilkS" user "B.Silkscreen")
		(1 "F.Mask" user)
		(3 "B.Mask" user)
		(17 "Dwgs.User" user "User.Drawings")
		(19 "Cmts.User" user "User.Comments")
		(21 "Eco1.User" user "User.Eco1")
		(23 "Eco2.User" user "User.Eco2")
		(25 "Edge.Cuts" user)
		(27 "Margin" user)
		(31 "F.CrtYd" user "F.Courtyard")
		(29 "B.CrtYd" user "B.Courtyard")
		(35 "F.Fab" user)
		(33 "B.Fab" user)
	)
	(footprint "antmicro-footprints:Fiducial_1mm_Mask2mm"
		(layer "F.Cu")
		(at 259.37 102.04)
		(descr "Circular Fiducial, 1mm bare copper, 3mm soldermask opening")
		(tags "fiducial")
		(property "Reference" "FID1006"
			(at 0 -1.4 0)
			(layer "F.SilkS")
			(hide yes)
			(effects
				(font
					(size 0.7 0.7)
					(thickness 0.15)
				)
				(justify left bottom)
			)
		)
		(property "Value" "Fiducial_1mm_Mask2mm"
			(at 0 2.2 0)
			(layer "F.Fab")
			(effects
				(font
					(size 0.7 0.7)
					(thickness 0.15)
				)
				(justify left bottom)
			)
		)
		(sheetfile "data-center-rdimm-ddr5-tester.kicad_sch")
		(attr board_only exclude_from_pos_files exclude_from_bom)
		(fp_circle
			(center 0 0)
			(end 1.24 0)
			(stroke
				(width 0.05)
				(type solid)
			)
			(fill no)
			(layer "F.CrtYd")
		)
		(fp_circle
			(center 0 0)
			(end 0.999 0)
			(stroke
				(width 0.15)
				(type solid)
			)
			(fill no)
			(layer "F.Fab")
		)
		(fp_text user "${REFERENCE}"
			(at -1.25 4.603 0)
			(layer "F.Fab")
			(effects
				(font
					(size 0.7 0.7)
					(thickness 0.15)
				)
				(justify left bottom)
			)
		)
		(fp_text user "License: Apache-2.0"
			(at -1.25 7.003 0)
			(layer "F.Fab")
			(effects
				(font
					(size 0.7 0.7)
					(thickness 0.15)
				)
				(justify left bottom)
			)
		)
		(fp_text user "Author: Antmicro"
			(at -1.25 5.803 0)
			(layer "F.Fab")
			(effects
				(font
					(size 0.7 0.7)
					(thickness 0.15)
				)
				(justify left bottom)
			)
		)
		(pad "" smd circle
			(at 0 0)
			(size 1 1)
			(layers "F.Cu" "F.Mask")
			(solder_mask_margin 0.5)
			(clearance 0.5)
		)
	)
	(footprint "antmicro-footprints:R_0603_1608Metric"
		(layer "F.Cu")
		(at 218.18 167.955 90)
		(descr "Resistor SMD 0603")
		(tags "resistor SMD 0603")
		(property "Reference" "R204"
			(at -0.02 -2.505 90)
			(layer "F.SilkS")
			(effects
				(font
					(size 0.7 0.7)
					(thickness 0.15)
				)
				(justify left bottom)
			)
		)
		(property "Value" "R_0R_22.4A_0603"
			(at 0 1.6 90)
			(layer "F.Fab")
			(effects
				(font
					(size 0.7 0.7)
					(thickness 0.15)
				)
				(justify left bottom)
			)
		)
		(property "Datasheet" "https://fscdn.rohm.com/en/products/databook/datasheet/passive/resistor/chip_resistor/pmr-jpw-e.pdf"
			(at 0 0 90)
			(layer "F.Fab")
			(hide yes)
			(effects
				(font
					(size 1.27 1.27)
					(thickness 0.15)
				)
			)
		)
		(property "Manufacturer" "ROHM Semiconductor"
			(at 0 0 90)
			(unlocked yes)
			(layer "F.Fab")
			(hide yes)
			(effects
				(font
					(size 1 1)
					(thickness 0.15)
				)
			)
		)
		(property "MPN" "PMR03EZPJ000"
			(at 0 0 90)
			(unlocked yes)
			(layer "F.Fab")
			(hide yes)
			(effects
				(font
					(size 1 1)
					(thickness 0.15)
				)
			)
		)
		(property "Val" "0R"
			(at 0 0 90)
			(unlocked yes)
			(layer "F.Fab")
			(hide yes)
			(effects
				(font
					(size 1 1)
					(thickness 0.15)
				)
			)
		)
		(property "Author" "Antmicro"
			(at 0 0 90)
			(unlocked yes)
			(layer "F.Fab")
			(hide yes)
			(effects
				(font
					(size 1 1)
					(thickness 0.15)
				)
			)
		)
		(property "License" "Apache-2.0"
			(at 0 0 90)
			(unlocked yes)
			(layer "F.Fab")
			(hide yes)
			(effects
				(font
					(size 1 1)
					(thickness 0.15)
				)
			)
		)
		(property "Max. Curr." "22.4A"
			(at 0 0 90)
			(unlocked yes)
			(layer "F.Fab")
			(hide yes)
			(effects
				(font
					(size 1 1)
					(thickness 0.15)
				)
			)
		)
		(sheetname "/Supply/DC-DC VCCINT/")
		(sheetfile "dc-dc-vccint.kicad_sch")
		(attr smd)
		(fp_line
			(start -0.15 -0.4)
			(end 0.15 -0.4)
			(stroke
				(width 0.15)
				(type solid)
			)
			(layer "F.SilkS")
		)
		(fp_line
			(start -0.15 0.4)
			(end 0.15 0.4)
			(stroke
				(width 0.15)
				(type solid)
			)
			(layer "F.SilkS")
		)
		(fp_rect
			(start -1.25 -0.65)
			(end 1.25 0.65)
			(stroke
				(width 0.05)
				(type solid)
			)
			(fill no)
			(layer "F.CrtYd")
		)
		(fp_rect
			(start -0.8 -0.4)
			(end 0.8 0.4)
			(stroke
				(width 0.15)
				(type solid)
			)
			(fill no)
			(layer "F.Fab")
		)
		(fp_text user "License: Apache-2.0"
			(at -1.25 5.9 90)
			(layer "F.Fab")
			(effects
				(font
					(size 0.7 0.7)
					(thickness 0.15)
				)
				(justify left bottom)
			)
		)
		(fp_text user "Author: Antmicro"
			(at -1.25 4.9 90)
			(layer "F.Fab")
			(effects
				(font
					(size 0.7 0.7)
					(thickness 0.15)
				)
				(justify left bottom)
			)
		)
		(fp_text user "${REFERENCE}"
			(at -1.25 3.898 90)
			(layer "F.Fab")
			(effects
				(font
					(size 0.7 0.7)
					(thickness 0.15)
				)
				(justify left bottom)
			)
		)
		(pad "1" smd roundrect
			(at -0.7 0 90)
			(size 0.8 1)
			(layers "F.Cu" "F.Mask" "F.Paste")
			(roundrect_rratio 0.2)
			(net 223 "/Supply/DC-DC VCCINT/0V85_REG0")
			(pintype "passive")
		)
		(pad "2" smd roundrect
			(at 0.7 0 90)
			(size 0.8 1)
			(layers "F.Cu" "F.Mask" "F.Paste")
			(roundrect_rratio 0.2)
			(net 553 "+0V85")
			(pintype "passive")
		)
	)
	(footprint "antmicro-footprints:Fiducial_1mm_Mask2mm"
		(layer "F.Cu")
		(at 113.585 186.315)
		(descr "Circular Fiducial, 1mm bare copper, 3mm soldermask opening")
		(tags "fiducial")
		(property "Reference" "FID1004"
			(at 0 -1.4 0)
			(layer "F.SilkS")
			(hide yes)
			(effects
				(font
					(size 0.7 0.7)
					(thickness 0.15)
				)
				(justify left bottom)
			)
		)
		(property "Value" "Fiducial_1mm_Mask2mm"
			(at 0 2.2 0)
			(layer "F.Fab")
			(effects
				(font
					(size 0.7 0.7)
					(thickness 0.15)
				)
				(justify left bottom)
			)
		)
		(sheetfile "data-center-rdimm-ddr5-tester.kicad_sch")
		(attr board_only exclude_from_pos_files exclude_from_bom)
		(fp_circle
			(center 0 0)
			(end 1.24 0)
			(stroke
				(width 0.05)
				(type solid)
			)
			(fill no)
			(layer "F.CrtYd")
		)
		(fp_circle
			(center 0 0)
			(end 0.999 0)
			(stroke
				(width 0.15)
				(type solid)
			)
			(fill no)
			(layer "F.Fab")
		)
		(fp_text user "Author: Antmicro"
			(at -1.25 5.803 0)
			(layer "F.Fab")
			(effects
				(font
					(size 0.7 0.7)
					(thickness 0.15)
				)
				(justify left bottom)
			)
		)
		(fp_text user "${REFERENCE}"
			(at -1.25 4.603 0)
			(layer "F.Fab")
			(effects
				(font
					(size 0.7 0.7)
					(thickness 0.15)
				)
				(justify left bottom)
			)
		)
		(fp_text user "License: Apache-2.0"
			(at -1.25 7.003 0)
			(layer "F.Fab")
			(effects
				(font
					(size 0.7 0.7)
					(thickness 0.15)
				)
				(justify left bottom)
			)
		)
		(pad "" smd circle
			(at 0 0)
			(size 1 1)
			(layers "F.Cu" "F.Mask")
			(solder_mask_margin 0.5)
			(clearance 0.5)
		)
	)
	(footprint "antmicro-footprints:R_0402_1005Metric"
		(layer "F.Cu")
		(at 252.785 142.4 180)
		(descr "Resistor SMD 0402")
		(tags "resistor SMD 0402")
		(property "Reference" "R62"
			(at -3.065 -0.5 0)
			(layer "F.SilkS")
			(effects
				(font
					(size 0.7 0.7)
					(thickness 0.15)
				)
				(justify right bottom)
			)
		)
		(property "Value" "R_330R_0402"
			(at -1.011843 1.772047 0)
			(layer "F.Fab")
			(effects
				(font
					(size 0.7 0.7)
					(thickness 0.15)
				)
				(justify right bottom)
			)
		)
		(property "Datasheet" "https://www.bourns.com/docs/product-datasheets/cr.pdf"
			(at 0 0 180)
			(layer "F.Fab")
			(hide yes)
			(effects
				(font
					(size 1.27 1.27)
					(thickness 0.15)
				)
			)
		)
		(property "Manufacturer" "Bourns"
			(at 0 0 180)
			(unlocked yes)
			(layer "F.Fab")
			(hide yes)
			(effects
				(font
					(size 1 1)
					(thickness 0.15)
				)
			)
		)
		(property "MPN" "CR0402-FX-3300GLF"
			(at 0 0 180)
			(unlocked yes)
			(layer "F.Fab")
			(hide yes)
			(effects
				(font
					(size 1 1)
					(thickness 0.15)
				)
			)
		)
		(property "Val" "330R"
			(at 0 0 180)
			(unlocked yes)
			(layer "F.Fab")
			(hide yes)
			(effects
				(font
					(size 1 1)
					(thickness 0.15)
				)
			)
		)
		(property "License" "Apache-2.0"
			(at 0 0 180)
			(unlocked yes)
			(layer "F.Fab")
			(hide yes)
			(effects
				(font
					(size 1 1)
					(thickness 0.15)
				)
			)
		)
		(property "Author" "Antmicro"
			(at 0 0 180)
			(unlocked yes)
			(layer "F.Fab")
			(hide yes)
			(effects
				(font
					(size 1 1)
					(thickness 0.15)
				)
			)
		)
		(property "Tolerance" "1%"
			(at 0 0 180)
			(unlocked yes)
			(layer "F.Fab")
			(hide yes)
			(effects
				(font
					(size 1 1)
					(thickness 0.15)
				)
			)
		)
		(sheetname "/DDR5 RDIMM/")
		(sheetfile "ddr5-rdimm.kicad_sch")
		(attr smd)
		(fp_rect
			(start -0.925 -0.47)
			(end 0.925 0.47)
			(stroke
				(width 0.05)
				(type default)
			)
			(fill no)
			(layer "F.CrtYd")
		)
		(fp_rect
			(start -0.5 -0.25)
			(end 0.5 0.25)
			(stroke
				(width 0.15)
				(type solid)
			)
			(fill no)
			(layer "F.Fab")
		)
		(fp_text user "Author: Antmicro"
			(at -0.95 4.169 180)
			(layer "F.Fab")
			(effects
				(font
					(size 0.7 0.7)
					(thickness 0.15)
				)
				(justify left bottom)
			)
		)
		(fp_text user "License: Apache-2.0"
			(at -0.95 5.169 180)
			(layer "F.Fab")
			(effects
				(font
					(size 0.7 0.7)
					(thickness 0.15)
				)
				(justify left bottom)
			)
		)
		(fp_text user "${REFERENCE}"
			(at -0.95 3.168 180)
			(layer "F.Fab")
			(effects
				(font
					(size 0.7 0.7)
					(thickness 0.15)
				)
				(justify left bottom)
			)
		)
		(pad "1" smd roundrect
			(at -0.48 0 180)
			(size 0.59 0.64)
			(layers "F.Cu" "F.Mask" "F.Paste")
			(roundrect_rratio 0.25)
			(net 236 "Net-(D20-C_{G})")
			(pintype "passive")
		)
		(pad "2" smd roundrect
			(at 0.48 0 180)
			(size 0.59 0.64)
			(layers "F.Cu" "F.Mask" "F.Paste")
			(roundrect_rratio 0.25)
			(net 278 "Net-(Q10-D)")
			(pintype "passive")
		)
	)
	(footprint "antmicro-footprints:R_0402_1005Metric"
		(layer "F.Cu")
		(at 120.975 170.775 90)
		(descr "Resistor SMD 0402")
		(tags "resistor SMD 0402")
		(property "Reference" "R248"
			(at 1.375 0.025 90)
			(layer "F.SilkS")
			(effects
				(font
					(size 0.7 0.7)
					(thickness 0.15)
				)
				(justify left bottom)
			)
		)
		(property "Value" "R_0R_0402"
			(at -1.011843 1.772047 90)
			(layer "F.Fab")
			(effects
				(font
					(size 0.7 0.7)
					(thickness 0.15)
				)
				(justify left bottom)
			)
		)
		(property "Datasheet" "https://industrial.panasonic.com/cdbs/www-data/pdf/RDA0000/AOA0000C301.pdf"
			(at 0 0 90)
			(layer "F.Fab")
			(hide yes)
			(effects
				(font
					(size 1.27 1.27)
					(thickness 0.15)
				)
			)
		)
		(property "MPN" "ERJ2GE0R00X"
			(at 0 0 90)
			(unlocked yes)
			(layer "F.Fab")
			(hide yes)
			(effects
				(font
					(size 1 1)
					(thickness 0.15)
				)
			)
		)
		(property "Manufacturer" "Panasonic"
			(at 0 0 90)
			(unlocked yes)
			(layer "F.Fab")
			(hide yes)
			(effects
				(font
					(size 1 1)
					(thickness 0.15)
				)
			)
		)
		(property "License" "Apache-2.0"
			(at 0 0 90)
			(unlocked yes)
			(layer "F.Fab")
			(hide yes)
			(effects
				(font
					(size 1 1)
					(thickness 0.15)
				)
			)
		)
		(property "Author" "Antmicro"
			(at 0 0 90)
			(unlocked yes)
			(layer "F.Fab")
			(hide yes)
			(effects
				(font
					(size 1 1)
					(thickness 0.15)
				)
			)
		)
		(property "Val" "0R"
			(at 0 0 90)
			(unlocked yes)
			(layer "F.Fab")
			(hide yes)
			(effects
				(font
					(size 1 1)
					(thickness 0.15)
				)
			)
		)
		(property "Tolerance" "~"
			(at 0 0 90)
			(unlocked yes)
			(layer "F.Fab")
			(hide yes)
			(effects
				(font
					(size 1 1)
					(thickness 0.15)
				)
			)
		)
		(property "Current" "1A"
			(at 0 0 90)
			(unlocked yes)
			(layer "F.Fab")
			(hide yes)
			(effects
				(font
					(size 1 1)
					(thickness 0.15)
				)
			)
		)
		(sheetname "/HDMI + SD Card/")
		(sheetfile "hdmi-sd-card.kicad_sch")
		(attr smd)
		(fp_rect
			(start -0.925 -0.47)
			(end 0.925 0.47)
			(stroke
				(width 0.05)
				(type default)
			)
			(fill no)
			(layer "F.CrtYd")
		)
		(fp_rect
			(start -0.5 -0.25)
			(end 0.5 0.25)
			(stroke
				(width 0.15)
				(type solid)
			)
			(fill no)
			(layer "F.Fab")
		)
		(fp_text user "License: Apache-2.0"
			(at -0.95 5.169 90)
			(layer "F.Fab")
			(effects
				(font
					(size 0.7 0.7)
					(thickness 0.15)
				)
				(justify left bottom)
			)
		)
		(fp_text user "Author: Antmicro"
			(at -0.95 4.169 90)
			(layer "F.Fab")
			(effects
				(font
					(size 0.7 0.7)
					(thickness 0.15)
				)
				(justify left bottom)
			)
		)
		(fp_text user "${REFERENCE}"
			(at -0.95 3.168 90)
			(layer "F.Fab")
			(effects
				(font
					(size 0.7 0.7)
					(thickness 0.15)
				)
				(justify left bottom)
			)
		)
		(pad "1" smd roundrect
			(at -0.48 0 90)
			(size 0.59 0.64)
			(layers "F.Cu" "F.Mask" "F.Paste")
			(roundrect_rratio 0.25)
			(net 810 "/HDMI + SD Card/HDMI_VDD")
			(pintype "passive")
		)
		(pad "2" smd roundrect
			(at 0.48 0 90)
			(size 0.59 0.64)
			(layers "F.Cu" "F.Mask" "F.Paste")
			(roundrect_rratio 0.25)
			(net 150 "+1V2")
			(pintype "passive")
		)
	)
	(footprint "antmicro-footprints:R_0402_1005Metric"
		(layer "F.Cu")
		(at 118.1 155.65)
		(descr "Resistor SMD 0402")
		(tags "resistor SMD 0402")
		(property "Reference" "R23"
			(at 1.85 0.575 0)
			(layer "F.SilkS")
			(effects
				(font
					(size 0.7 0.7)
					(thickness 0.15)
				)
				(justify left bottom)
			)
		)
		(property "Value" "R_10k_0402"
			(at -1.011843 1.772047 0)
			(layer "F.Fab")
			(effects
				(font
					(size 0.7 0.7)
					(thickness 0.15)
				)
				(justify left bottom)
			)
		)
		(property "Datasheet" "https://www.bourns.com/docs/product-datasheets/cr.pdf"
			(at 0 0 0)
			(layer "F.Fab")
			(hide yes)
			(effects
				(font
					(size 1.27 1.27)
					(thickness 0.15)
				)
			)
		)
		(property "MPN" "CR0402-FX-1002GLF"
			(at 0 0 0)
			(unlocked yes)
			(layer "F.Fab")
			(hide yes)
			(effects
				(font
					(size 1 1)
					(thickness 0.15)
				)
			)
		)
		(property "Manufacturer" "Bourns"
			(at 0 0 0)
			(unlocked yes)
			(layer "F.Fab")
			(hide yes)
			(effects
				(font
					(size 1 1)
					(thickness 0.15)
				)
			)
		)
		(property "License" "Apache-2.0"
			(at 0 0 0)
			(unlocked yes)
			(layer "F.Fab")
			(hide yes)
			(effects
				(font
					(size 1 1)
					(thickness 0.15)
				)
			)
		)
		(property "Author" "Antmicro"
			(at 0 0 0)
			(unlocked yes)
			(layer "F.Fab")
			(hide yes)
			(effects
				(font
					(size 1 1)
					(thickness 0.15)
				)
			)
		)
		(property "Val" "10k"
			(at 0 0 0)
			(unlocked yes)
			(layer "F.Fab")
			(hide yes)
			(effects
				(font
					(size 1 1)
					(thickness 0.15)
				)
			)
		)
		(property "Tolerance" "1%"
			(at 0 0 0)
			(unlocked yes)
			(layer "F.Fab")
			(hide yes)
			(effects
				(font
					(size 1 1)
					(thickness 0.15)
				)
			)
		)
		(sheetname "/HDMI + SD Card/")
		(sheetfile "hdmi-sd-card.kicad_sch")
		(attr smd)
		(fp_rect
			(start -0.925 -0.47)
			(end 0.925 0.47)
			(stroke
				(width 0.05)
				(type default)
			)
			(fill no)
			(layer "F.CrtYd")
		)
		(fp_rect
			(start -0.5 -0.25)
			(end 0.5 0.25)
			(stroke
				(width 0.15)
				(type solid)
			)
			(fill no)
			(layer "F.Fab")
		)
		(fp_text user "License: Apache-2.0"
			(at -0.95 5.169 0)
			(layer "F.Fab")
			(effects
				(font
					(size 0.7 0.7)
					(thickness 0.15)
				)
				(justify left bottom)
			)
		)
		(fp_text user "Author: Antmicro"
			(at -0.95 4.169 0)
			(layer "F.Fab")
			(effects
				(font
					(size 0.7 0.7)
					(thickness 0.15)
				)
				(justify left bottom)
			)
		)
		(fp_text user "${REFERENCE}"
			(at -0.95 3.168 0)
			(layer "F.Fab")
			(effects
				(font
					(size 0.7 0.7)
					(thickness 0.15)
				)
				(justify left bottom)
			)
		)
		(pad "1" smd roundrect
			(at -0.48 0)
			(size 0.59 0.64)
			(layers "F.Cu" "F.Mask" "F.Paste")
			(roundrect_rratio 0.25)
			(net 635 "/FPGA banks HP/SD.CD")
			(pintype "passive")
		)
		(pad "2" smd roundrect
			(at 0.48 0)
			(size 0.59 0.64)
			(layers "F.Cu" "F.Mask" "F.Paste")
			(roundrect_rratio 0.25)
			(net 797 "+1V8")
			(pintype "passive")
		)
	)
	(footprint "antmicro-footprints:R_0402_1005Metric"
		(layer "F.Cu")
		(at 121.681 166.1125 90)
		(descr "Resistor SMD 0402")
		(tags "resistor SMD 0402")
		(property "Reference" "R228"
			(at 0.9125 3.969 90)
			(layer "F.SilkS")
			(effects
				(font
					(size 0.7 0.7)
					(thickness 0.15)
				)
				(justify left bottom)
			)
		)
		(property "Value" "R_64k9_0402"
			(at -1.011843 1.772047 90)
			(layer "F.Fab")
			(effects
				(font
					(size 0.7 0.7)
					(thickness 0.15)
				)
				(justify left bottom)
			)
		)
		(property "Datasheet" "https://www.bourns.com/docs/product-datasheets/cr.pdf"
			(at 0 0 90)
			(layer "F.Fab")
			(hide yes)
			(effects
				(font
					(size 1.27 1.27)
					(thickness 0.15)
				)
			)
		)
		(property "MPN" "CR0402-FX-6492GLF"
			(at 0 0 90)
			(unlocked yes)
			(layer "F.Fab")
			(hide yes)
			(effects
				(font
					(size 1 1)
					(thickness 0.15)
				)
			)
		)
		(property "Manufacturer" "Bourns"
			(at 0 0 90)
			(unlocked yes)
			(layer "F.Fab")
			(hide yes)
			(effects
				(font
					(size 1 1)
					(thickness 0.15)
				)
			)
		)
		(property "License" "Apache-2.0"
			(at 0 0 90)
			(unlocked yes)
			(layer "F.Fab")
			(hide yes)
			(effects
				(font
					(size 1 1)
					(thickness 0.15)
				)
			)
		)
		(property "Author" "Antmicro"
			(at 0 0 90)
			(unlocked yes)
			(layer "F.Fab")
			(hide yes)
			(effects
				(font
					(size 1 1)
					(thickness 0.15)
				)
			)
		)
		(property "Val" "64k9"
			(at 0 0 90)
			(unlocked yes)
			(layer "F.Fab")
			(hide yes)
			(effects
				(font
					(size 1 1)
					(thickness 0.15)
				)
			)
		)
		(property "Tolerance" "1%"
			(at 0 0 90)
			(unlocked yes)
			(layer "F.Fab")
			(hide yes)
			(effects
				(font
					(size 1 1)
					(thickness 0.15)
				)
			)
		)
		(sheetname "/HDMI + SD Card/")
		(sheetfile "hdmi-sd-card.kicad_sch")
		(attr smd exclude_from_bom dnp)
		(fp_rect
			(start -0.925 -0.47)
			(end 0.925 0.47)
			(stroke
				(width 0.05)
				(type default)
			)
			(fill no)
			(layer "F.CrtYd")
		)
		(fp_rect
			(start -0.5 -0.25)
			(end 0.5 0.25)
			(stroke
				(width 0.15)
				(type solid)
			)
			(fill no)
			(layer "F.Fab")
		)
		(fp_text user "Author: Antmicro"
			(at -0.95 4.169 90)
			(layer "F.Fab")
			(effects
				(font
					(size 0.7 0.7)
					(thickness 0.15)
				)
				(justify left bottom)
			)
		)
		(fp_text user "License: Apache-2.0"
			(at -0.95 5.169 90)
			(layer "F.Fab")
			(effects
				(font
					(size 0.7 0.7)
					(thickness 0.15)
				)
				(justify left bottom)
			)
		)
		(fp_text user "${REFERENCE}"
			(at -0.95 3.168 90)
			(layer "F.Fab")
			(effects
				(font
					(size 0.7 0.7)
					(thickness 0.15)
				)
				(justify left bottom)
			)
		)
		(pad "1" smd roundrect
			(at -0.48 0 90)
			(size 0.59 0.64)
			(layers "F.Cu" "F.Mask" "F.Paste")
			(roundrect_rratio 0.25)
			(net 738 "/HDMI + SD Card/~{HDMI_SEL}")
			(pintype "passive")
		)
		(pad "2" smd roundrect
			(at 0.48 0 90)
			(size 0.59 0.64)
			(layers "F.Cu" "F.Mask" "F.Paste")
			(roundrect_rratio 0.25)
			(net 151 "+3V3")
			(pintype "passive")
		)
	)
)
